# S9S_MB_2U (Grand Teton) — schematic netlist excerpt (pin names and nets, part order shuffled) for the footprints in the layout excerpt that follows; sources: Cadence DE-HDL packaged netlist, KiCad conversion of 03242023_DA0F0TMBIJ0_F0T_Motherboard_J_brd_V01_OCP.brd

J12  SCONN288_ADR50017P087CC  SCONN288_ADR50017-P087CC IO  pkg DDR288S_1-1VXB  page 93
  VIN_BULK0  = P12V_S3_AUX_CPU0_NVDIMM
  RFU0  = TP_CHF_CPU0_DIMM2_FRU_0
  VIN_MGMT  = P3V3_AUX
  HSCL  = I3C_SPD_DDREFGH_CPU0_LVC1_SCL_3
  HSDA  = I3C_SPD_DDREFGH_CPU0_LVC1_SDA
  VSS0  = GND
  DQ0_A  = M_F_CPU0_SA_DQ<0>
  VSS1  = GND
  DQ1_A  = M_F_CPU0_SA_DQ<1>
  VSS2  = GND
  DQS0_A_T  = M_F_CPU0_SA_DQS_DP<0>
  DQS0_A_C  = M_F_CPU0_SA_DQS_DN<0>
  VSS3  = GND
  DQ4_A  = M_F_CPU0_SA_DQ<4>
  VSS4  = GND
  DQ5_A  = M_F_CPU0_SA_DQ<5>
  VSS5  = GND
  DQ8_A  = M_F_CPU0_SA_DQ<8>
  VSS6  = GND
  DQ9_A  = M_F_CPU0_SA_DQ<9>
  VSS7  = GND
  DQS1_A_T  = M_F_CPU0_SA_DQS_DP<1>
  DQS1_A_C  = M_F_CPU0_SA_DQS_DN<1>
  VSS8  = GND
  DQ12_A  = M_F_CPU0_SA_DQ<12>
  VSS9  = GND
  DQ13_A  = M_F_CPU0_SA_DQ<13>
  VSS10  = GND
  DQ16_A  = M_F_CPU0_SA_DQ<16>
  VSS11  = GND
  DQ17_A  = M_F_CPU0_SA_DQ<17>
  VSS12  = GND
  DQS2_A_T  = M_F_CPU0_SA_DQS_DP<2>
  DQS2_A_C  = M_F_CPU0_SA_DQS_DN<2>
  VSS13  = GND
  DQ20_A  = M_F_CPU0_SA_DQ<20>
  VSS14  = GND
  DQ21_A  = M_F_CPU0_SA_DQ<21>
  VSS15  = GND
  DQ24_A  = M_F_CPU0_SA_DQ<24>
  VSS16  = GND
  DQ25_A  = M_F_CPU0_SA_DQ<25>
  VSS17  = GND
  DQS3_A_T  = M_F_CPU0_SA_DQS_DP<3>
  DQS3_A_C  = M_F_CPU0_SA_DQS_DN<3>
  VSS18  = GND
  DQ28_A  = M_F_CPU0_SA_DQ<28>
  VSS19  = GND
  DQ29_A  = M_F_CPU0_SA_DQ<29>
  VSS20  = GND
  CB0_A  = M_F_CPU0_SA_CB<0>
  VSS21  = GND
  CB1_A  = M_F_CPU0_SA_CB<1>
  VSS22  = GND
  DQS4_A_T  = M_F_CPU0_SA_DQS_DP<4>
  DQS4_A_C  = M_F_CPU0_SA_DQS_DN<4>
  VSS23  = GND
  CB4_A  = M_F_CPU0_SA_CB<4>
  VSS24  = GND
  CB5_A  = M_F_CPU0_SA_CB<5>
  VSS25  = GND
  ALERT_N  = M_F_CPU0_ALERT_N
  VSS26  = GND
  CS0_A_N  = M_F_CPU0_SA_CS_N<2>
  VSS27  = GND
  CA0_A  = M_F_CPU0_SA_CA<0>
  VSS28  = GND
  CA2_A  = M_F_CPU0_SA_CA<2>
  VSS29  = GND
  CA4_A  = M_F_CPU0_SA_CA<4>
  VSS30  = GND
  CA6_A  = M_F_CPU0_SA_CA<6>
  VSS31  = GND
  PAR_A  = M_F_CPU0_SA_PAR
  VSS32  = GND
  CA0_B  = M_F_CPU0_SB_CA<0>
  VSS33  = GND
  CA2_B  = M_F_CPU0_SB_CA<2>
  VSS34  = GND
  CA4_B  = M_F_CPU0_SB_CA<4>
  VSS35  = GND
  CA6_B  = M_F_CPU0_SB_CA<6>
  VSS36  = GND
  CS0_B_N  = M_F_CPU0_SB_CS_N<2>
  VSS37  = GND
  \lbd||rsp_a_n\  = M_F_CPU0_SA_RSP<1>
  \lbs||rsp_b_n\  = M_F_CPU0_SB_RSP<1>
  VSS38  = GND
  CB4_B  = M_F_CPU0_SB_CB<4>
  VSS39  = GND
  CB5_B  = M_F_CPU0_SB_CB<5>
  VSS40  = GND
  \dqs9_b_t||tdqs9_b_t||dbi4_b_n\  = M_F_CPU0_SB_DQS_DP<9>
  \dqs9_b_c||tdqs9_b_c\  = M_F_CPU0_SB_DQS_DN<9>
  VSS41  = GND
  CB0_B  = M_F_CPU0_SB_CB<0>
  VSS42  = GND
  CB1_B  = M_F_CPU0_SB_CB<1>
  VSS43  = GND
  DQ0_B  = M_F_CPU0_SB_DQ<0>
  VSS44  = GND
  DQ1_B  = M_F_CPU0_SB_DQ<1>
  VSS45  = GND
  DQS0_B_T  = M_F_CPU0_SB_DQS_DP<0>
  DQS0_B_C  = M_F_CPU0_SB_DQS_DN<0>
  VSS46  = GND
  DQ4_B  = M_F_CPU0_SB_DQ<4>
  VSS47  = GND
  DQ5_B  = M_F_CPU0_SB_DQ<5>
  VSS48  = GND
  DQ8_B  = M_F_CPU0_SB_DQ<8>
  VSS49  = GND
  DQ9_B  = M_F_CPU0_SB_DQ<9>
  VSS50  = GND
  DQS1_B_T  = M_F_CPU0_SB_DQS_DP<1>
  DQS1_B_C  = M_F_CPU0_SB_DQS_DN<1>
  VSS51  = GND
  DQ12_B  = M_F_CPU0_SB_DQ<12>
  VSS52  = GND
  DQ13_B  = M_F_CPU0_SB_DQ<13>
  VSS53  = GND
  DQ16_B  = M_F_CPU0_SB_DQ<16>
  VSS54  = GND
  DQ17_B  = M_F_CPU0_SB_DQ<17>
  VSS55  = GND
  DQS2_B_T  = M_F_CPU0_SB_DQS_DP<2>
  DQS2_B_C  = M_F_CPU0_SB_DQS_DN<2>
  VSS56  = GND
  DQ20_B  = M_F_CPU0_SB_DQ<20>
  VSS57  = GND
  DQ21_B  = M_F_CPU0_SB_DQ<21>
  VSS58  = GND
  DQ24_B  = M_F_CPU0_SB_DQ<24>
  VSS59  = GND
  DQ25_B  = M_F_CPU0_SB_DQ<25>
  VSS60  = GND
  DQS3_B_T  = M_F_CPU0_SB_DQS_DP<3>
  DQS3_B_C  = M_F_CPU0_SB_DQS_DN<3>
  VSS61  = GND
  DQ28_B  = M_F_CPU0_SB_DQ<28>
  VSS62  = GND
  DQ29_B  = M_F_CPU0_SB_DQ<29>
  VSS63  = GND
  RFU1  = TP_CHF_CPU0_DIMM2_FRU_1
  VIN_BULK1  = P12V_S3_AUX_CPU0_NVDIMM
  VIN_BULK2  = P12V_S3_AUX_CPU0_NVDIMM
  \pwr_good||fail_n\  = PWRGD_CHF_CPU0_DIMM2
  HSA  = PD_CHF_CPU0_DIMM2_SAA
  RFU2  = TP_CHF_CPU0_DIMM2_FRU_2
  RFU3  = TP_CHF_CPU0_DIMM2_FRU_3
  VSS64  = GND
  DQ2_A  = M_F_CPU0_SA_DQ<2>
  VSS65  = GND
  DQ3_A  = M_F_CPU0_SA_DQ<3>
  VSS66  = GND
  \dqs5_a_c||tdqs5_a_c||dqs5_a_t||tdqs5_a_t\  = M_F_CPU0_SA_DQS_DN<5>
  \dqs5_a_t||tdqs5_a_t\  = M_F_CPU0_SA_DQS_DP<5>
  VSS67  = GND
  DQ6_A  = M_F_CPU0_SA_DQ<6>
  VSS68  = GND
  DQ7_A  = M_F_CPU0_SA_DQ<7>
  VSS69  = GND
  DQ10_A  = M_F_CPU0_SA_DQ<10>
  VSS70  = GND
  DQ11_A  = M_F_CPU0_SA_DQ<11>
  VSS71  = GND
  \dqs6_a_c||tdqs6_a_c||dqs6_a_t||tdqs6_a_t\  = M_F_CPU0_SA_DQS_DN<6>
  \dqs6_a_t||tdqs6_a_t\  = M_F_CPU0_SA_DQS_DP<6>
  VSS72  = GND
  DQ14_A  = M_F_CPU0_SA_DQ<14>
  VSS73  = GND
  DQ15_A  = M_F_CPU0_SA_DQ<15>
  VSS74  = GND
  DQ18_A  = M_F_CPU0_SA_DQ<18>
  VSS75  = GND
  DQ19_A  = M_F_CPU0_SA_DQ<19>
  VSS76  = GND
  \dqs7_a_c||tdqs7_a_c\  = M_F_CPU0_SA_DQS_DN<7>
  \dqs7_a_t||tdqs7_a_t\  = M_F_CPU0_SA_DQS_DP<7>
  VSS77  = GND
  DQ22_A  = M_F_CPU0_SA_DQ<22>
  VSS78  = GND
  DQ23_A  = M_F_CPU0_SA_DQ<23>
  VSS79  = GND
  DQ26_A  = M_F_CPU0_SA_DQ<26>
  VSS80  = GND
  DQ27_A  = M_F_CPU0_SA_DQ<27>
  VSS81  = GND
  \dqs8_a_c||tdqs8_a_c\  = M_F_CPU0_SA_DQS_DN<8>
  \dqs8_a_t||tdqs8_a_t\  = M_F_CPU0_SA_DQS_DP<8>
  VSS82  = GND
  DQ30_A  = M_F_CPU0_SA_DQ<30>
  VSS83  = GND
  DQ31_A  = M_F_CPU0_SA_DQ<31>
  VSS84  = GND
  CB2_A  = M_F_CPU0_SA_CB<2>
  VSS85  = GND
  CB3_A  = M_F_CPU0_SA_CB<3>
  VSS86  = GND
  \dqs9_a_c||tdqs9_a_c\  = M_F_CPU0_SA_DQS_DN<9>
  \dqs9_a_t||tdqs9_a_t\  = M_F_CPU0_SA_DQS_DP<9>
  VSS87  = GND
  CB6_A  = M_F_CPU0_SA_CB<6>
  VSS88  = GND
  CB7_A  = M_F_CPU0_SA_CB<7>
  VSS89  = GND
  RESET_N  = RST_M_EF_CPU0_FPGA_N
  VSS90  = GND
  CS1_A_N  = M_F_CPU0_SA_CS_N<3>
  VSS91  = GND
  CA1_A  = M_F_CPU0_SA_CA<1>
  VSS92  = GND
  CA3_A  = M_F_CPU0_SA_CA<3>
  VSS93  = GND
  CA5_A  = M_F_CPU0_SA_CA<5>
  VSS94  = GND
  CK_T  = M_F_CPU0_CLK_DP<1>
  CK_C  = M_F_CPU0_CLK_DN<1>
  VSS95  = GND
  RFU4  = TP_CHF_CPU0_DIMM2_FRU_4
  CA1_B  = M_F_CPU0_SB_CA<1>
  VSS96  = GND
  CA3_B  = M_F_CPU0_SB_CA<3>
  VSS97  = GND
  CA5_B  = M_F_CPU0_SB_CA<5>
  VSS98  = GND
  PAR_B  = M_F_CPU0_SB_PAR
  VSS99  = GND
  CS1_B_N  = M_F_CPU0_SB_CS_N<3>
  VSS100  = GND
  RFU5  = TP_CHF_CPU0_DIMM2_FRU_5
  RFU6  = TP_CHF_CPU0_DIMM2_FRU_6
  VSS101  = GND
  CB6_B  = M_F_CPU0_SB_CB<6>
  VSS102  = GND
  CB7_B  = M_F_CPU0_SB_CB<7>
  VSS103  = GND
  DQS4_B_C  = M_F_CPU0_SB_DQS_DN<4>
  DQS4_B_T  = M_F_CPU0_SB_DQS_DP<4>
  VSS104  = GND
  CB2_B  = M_F_CPU0_SB_CB<2>
  VSS105  = GND
  CB3_B  = M_F_CPU0_SB_CB<3>
  VSS106  = GND
  DQ2_B  = M_F_CPU0_SB_DQ<2>
  VSS107  = GND
  DQ3_B  = M_F_CPU0_SB_DQ<3>
  VSS108  = GND
  \dqs5_b_c||tdqs5_b_c\  = M_F_CPU0_SB_DQS_DN<5>
  \dqs5_b_t||tdqs5_b_t\  = M_F_CPU0_SB_DQS_DP<5>
  VSS109  = GND
  DQ6_B  = M_F_CPU0_SB_DQ<6>
  VSS110  = GND
  DQ7_B  = M_F_CPU0_SB_DQ<7>
  VSS111  = GND
  DQ10_B  = M_F_CPU0_SB_DQ<10>
  VSS112  = GND
  DQ11_B  = M_F_CPU0_SB_DQ<11>
  VSS113  = GND
  \dqs6_b_c||tdqs6_b_c\  = M_F_CPU0_SB_DQS_DN<6>
  \dqs6_b_t||tdqs6_b_t\  = M_F_CPU0_SB_DQS_DP<6>
  VSS114  = GND
  DQ14_B  = M_F_CPU0_SB_DQ<14>
  VSS115  = GND
  DQ15_B  = M_F_CPU0_SB_DQ<15>
  VSS116  = GND
  DQ18_B  = M_F_CPU0_SB_DQ<18>
  VSS117  = GND
  DQ19_B  = M_F_CPU0_SB_DQ<19>
  VSS118  = GND
  \dqs7_b_c||tdqs7_b_c\  = M_F_CPU0_SB_DQS_DN<7>
  \dqs7_b_t||tdqs7_b_t\  = M_F_CPU0_SB_DQS_DP<7>
  VSS119  = GND
  DQ22_B  = M_F_CPU0_SB_DQ<22>
  VSS120  = GND
  DQ23_B  = M_F_CPU0_SB_DQ<23>
  VSS121  = GND
  DQ26_B  = M_F_CPU0_SB_DQ<26>
  VSS122  = GND
  DQ27_B  = M_F_CPU0_SB_DQ<27>
  VSS123  = GND
  \dqs8_b_c||tdqs8_b_c\  = M_F_CPU0_SB_DQS_DN<8>
  \dqs8_b_t||tdqs8_b_t\  = M_F_CPU0_SB_DQS_DP<8>
  VSS124  = GND
  DQ30_B  = M_F_CPU0_SB_DQ<30>
  VSS125  = GND
  DQ31_B  = M_F_CPU0_SB_DQ<31>
  VSS126  = GND
  G1  = GND
  G2  = GND
  G3  = GND

(kicad_pcb
	(version 20260206)
	(generator "pcbnew")
	(generator_version "10.0")
	(general
		(thickness 1.6)
		(legacy_teardrops no)
	)
	(paper "A4")
	(title_block
		(title "03242023_DA0F0TMBIJ0_F0T_Motherboard_J_brd_V01_OCP.brd")
		(comment 1 "Grand Teton / footprint 3198 of 6105 (J12), pads 138-182 of 291")
	)
	(layers
		(0 "F.Cu" signal "TOP")
		(4 "In1.Cu" signal "GND")
		(6 "In2.Cu" signal "IN1")
		(8 "In3.Cu" signal "GND1")
		(10 "In4.Cu" signal "IN2")
		(12 "In5.Cu" signal "GND2")
		(14 "In6.Cu" signal "IN3")
		(16 "In7.Cu" signal "GND3")
		(18 "In8.Cu" signal "VCC")
		(20 "In9.Cu" signal "VCC1")
		(22 "In10.Cu" signal "GND4")
		(24 "In11.Cu" signal "IN4")
		(26 "In12.Cu" signal "GND5")
		(28 "In13.Cu" signal "IN5")
		(30 "In14.Cu" signal "GND6")
		(32 "In15.Cu" signal "IN6")
		(34 "In16.Cu" signal "GND7")
		(2 "B.Cu" signal "BOTTOM")
		(9 "F.Adhes" user "F.Adhesive")
		(11 "B.Adhes" user "B.Adhesive")
		(13 "F.Paste" user "Package Geometry/Pastemask Top")
		(15 "B.Paste" user "Package Geometry/Pastemask Bottom")
		(5 "F.SilkS" user "Ref Des/Silkscreen Top")
		(7 "B.SilkS" user "Ref Des/Silkscreen Bottom")
		(1 "F.Mask" user "Board Geometry/Soldermask Top")
		(3 "B.Mask" user "Board Geometry/Soldermask Bottom")
		(17 "Dwgs.User" user "User.Drawings")
		(19 "Cmts.User" user "User.Comments")
		(21 "Eco1.User" user "User.Eco1")
		(23 "Eco2.User" user "User.Eco2")
		(25 "Edge.Cuts" user "Board Geometry/Outline")
		(27 "Margin" user)
		(31 "F.CrtYd" user "Package Geometry/Place Bound Top")
		(29 "B.CrtYd" user "Package Geometry/Place Bound Bottom")
		(35 "F.Fab" user "Ref Des/Assembly Top")
		(33 "B.Fab" user "Ref Des/Assembly Bottom")
	)
	(footprint ""
		(layer "F.Cu")
		(at 423.890948 -258.091686)
		(property "Reference" "J12"
			(at -3.683 -81.702148 0)
			(unlocked yes)
			(layer "F.SilkS")
			(effects
				(font
					(size 0.7874 0.5842)
					(thickness 0.1524)
				)
				(justify left)
			)
		)
		(property "Value" ""
			(at 0 0 0)
			(layer "F.Fab")
			(effects
				(font
					(size 1.27 1.27)
				)
			)
		)
		(duplicate_pad_numbers_are_jumpers no)
		(pad "138" smd rect
			(at -2.050034 58.224928 270)
			(size 0.519938 1.4986)
			(layers "F.Cu" "F.Mask" "F.Paste")
			(net "M_F_CPU0_SB_DQS_DN<3>")
		)
		(pad "139" smd rect
			(at -2.050034 59.075066 270)
			(size 0.519938 1.4986)
			(layers "F.Cu" "F.Mask" "F.Paste")
			(net "GND")
		)
		(pad "140" smd rect
			(at -2.050034 59.92495 270)
			(size 0.519938 1.4986)
			(layers "F.Cu" "F.Mask" "F.Paste")
			(net "M_F_CPU0_SB_DQ<28>")
		)
		(pad "141" smd rect
			(at -2.050034 60.775088 270)
			(size 0.519938 1.4986)
			(layers "F.Cu" "F.Mask" "F.Paste")
			(net "GND")
		)
		(pad "142" smd rect
			(at -2.050034 61.624972 270)
			(size 0.519938 1.4986)
			(layers "F.Cu" "F.Mask" "F.Paste")
			(net "M_F_CPU0_SB_DQ<29>")
		)
		(pad "143" smd rect
			(at -2.050034 62.47511 270)
			(size 0.519938 1.4986)
			(layers "F.Cu" "F.Mask" "F.Paste")
			(net "GND")
		)
		(pad "144" smd rect
			(at -2.050034 63.324994 270)
			(size 0.519938 1.4986)
			(layers "F.Cu" "F.Mask" "F.Paste")
			(net "TP_CHF_CPU0_DIMM2_FRU_1")
		)
		(pad "145" smd rect
			(at 2.050034 -63.324994 270)
			(size 0.519938 1.4986)
			(layers "F.Cu" "F.Mask" "F.Paste")
			(net "P12V_S3_AUX_CPU0_NVDIMM")
		)
		(pad "146" smd rect
			(at 2.050034 -62.47511 270)
			(size 0.519938 1.4986)
			(layers "F.Cu" "F.Mask" "F.Paste")
			(net "P12V_S3_AUX_CPU0_NVDIMM")
		)
		(pad "147" smd rect
			(at 2.050034 -61.624972 270)
			(size 0.519938 1.4986)
			(layers "F.Cu" "F.Mask" "F.Paste")
			(net "PWRGD_CHF_CPU0_DIMM2")
		)
		(pad "148" smd rect
			(at 2.050034 -60.775088 270)
			(size 0.519938 1.4986)
			(layers "F.Cu" "F.Mask" "F.Paste")
			(net "PD_CHF_CPU0_DIMM2_SAA")
		)
		(pad "149" smd rect
			(at 2.050034 -59.92495 270)
			(size 0.519938 1.4986)
			(layers "F.Cu" "F.Mask" "F.Paste")
			(net "TP_CHF_CPU0_DIMM2_FRU_2")
		)
		(pad "150" smd rect
			(at 2.050034 -59.075066 270)
			(size 0.519938 1.4986)
			(layers "F.Cu" "F.Mask" "F.Paste")
			(net "TP_CHF_CPU0_DIMM2_FRU_3")
		)
		(pad "151" smd rect
			(at 2.050034 -58.224928 270)
			(size 0.519938 1.4986)
			(layers "F.Cu" "F.Mask" "F.Paste")
			(net "GND")
		)
		(pad "152" smd rect
			(at 2.050034 -57.375044 270)
			(size 0.519938 1.4986)
			(layers "F.Cu" "F.Mask" "F.Paste")
			(net "M_F_CPU0_SA_DQ<2>")
		)
		(pad "153" smd rect
			(at 2.050034 -56.524906 270)
			(size 0.519938 1.4986)
			(layers "F.Cu" "F.Mask" "F.Paste")
			(net "GND")
		)
		(pad "154" smd rect
			(at 2.050034 -55.675022 270)
			(size 0.519938 1.4986)
			(layers "F.Cu" "F.Mask" "F.Paste")
			(net "M_F_CPU0_SA_DQ<3>")
		)
		(pad "155" smd rect
			(at 2.050034 -54.824884 270)
			(size 0.519938 1.4986)
			(layers "F.Cu" "F.Mask" "F.Paste")
			(net "GND")
		)
		(pad "156" smd rect
			(at 2.050034 -53.975 270)
			(size 0.519938 1.4986)
			(layers "F.Cu" "F.Mask" "F.Paste")
			(net "M_F_CPU0_SA_DQS_DN<5>")
		)
		(pad "157" smd rect
			(at 2.050034 -53.125116 270)
			(size 0.519938 1.4986)
			(layers "F.Cu" "F.Mask" "F.Paste")
			(net "M_F_CPU0_SA_DQS_DP<5>")
		)
		(pad "158" smd rect
			(at 2.050034 -52.274978 270)
			(size 0.519938 1.4986)
			(layers "F.Cu" "F.Mask" "F.Paste")
			(net "GND")
		)
		(pad "159" smd rect
			(at 2.050034 -51.425094 270)
			(size 0.519938 1.4986)
			(layers "F.Cu" "F.Mask" "F.Paste")
			(net "M_F_CPU0_SA_DQ<6>")
		)
		(pad "160" smd rect
			(at 2.050034 -50.574956 270)
			(size 0.519938 1.4986)
			(layers "F.Cu" "F.Mask" "F.Paste")
			(net "GND")
		)
		(pad "161" smd rect
			(at 2.050034 -49.725072 270)
			(size 0.519938 1.4986)
			(layers "F.Cu" "F.Mask" "F.Paste")
			(net "M_F_CPU0_SA_DQ<7>")
		)
		(pad "162" smd rect
			(at 2.050034 -48.874934 270)
			(size 0.519938 1.4986)
			(layers "F.Cu" "F.Mask" "F.Paste")
			(net "GND")
		)
		(pad "163" smd rect
			(at 2.050034 -48.02505 270)
			(size 0.519938 1.4986)
			(layers "F.Cu" "F.Mask" "F.Paste")
			(net "M_F_CPU0_SA_DQ<10>")
		)
		(pad "164" smd rect
			(at 2.050034 -47.174912 270)
			(size 0.519938 1.4986)
			(layers "F.Cu" "F.Mask" "F.Paste")
			(net "GND")
		)
		(pad "165" smd rect
			(at 2.050034 -46.325028 270)
			(size 0.519938 1.4986)
			(layers "F.Cu" "F.Mask" "F.Paste")
			(net "M_F_CPU0_SA_DQ<11>")
		)
		(pad "166" smd rect
			(at 2.050034 -45.47489 270)
			(size 0.519938 1.4986)
			(layers "F.Cu" "F.Mask" "F.Paste")
			(net "GND")
		)
		(pad "167" smd rect
			(at 2.050034 -44.625006 270)
			(size 0.519938 1.4986)
			(layers "F.Cu" "F.Mask" "F.Paste")
			(net "M_F_CPU0_SA_DQS_DN<6>")
		)
		(pad "168" smd rect
			(at 2.050034 -43.775122 270)
			(size 0.519938 1.4986)
			(layers "F.Cu" "F.Mask" "F.Paste")
			(net "M_F_CPU0_SA_DQS_DP<6>")
		)
		(pad "169" smd rect
			(at 2.050034 -42.924984 270)
			(size 0.519938 1.4986)
			(layers "F.Cu" "F.Mask" "F.Paste")
			(net "GND")
		)
		(pad "170" smd rect
			(at 2.050034 -42.0751 270)
			(size 0.519938 1.4986)
			(layers "F.Cu" "F.Mask" "F.Paste")
			(net "M_F_CPU0_SA_DQ<14>")
		)
		(pad "171" smd rect
			(at 2.050034 -41.224962 270)
			(size 0.519938 1.4986)
			(layers "F.Cu" "F.Mask" "F.Paste")
			(net "GND")
		)
		(pad "172" smd rect
			(at 2.050034 -40.375078 270)
			(size 0.519938 1.4986)
			(layers "F.Cu" "F.Mask" "F.Paste")
			(net "M_F_CPU0_SA_DQ<15>")
		)
		(pad "173" smd rect
			(at 2.050034 -39.52494 270)
			(size 0.519938 1.4986)
			(layers "F.Cu" "F.Mask" "F.Paste")
			(net "GND")
		)
		(pad "174" smd rect
			(at 2.050034 -38.675056 270)
			(size 0.519938 1.4986)
			(layers "F.Cu" "F.Mask" "F.Paste")
			(net "M_F_CPU0_SA_DQ<18>")
		)
		(pad "175" smd rect
			(at 2.050034 -37.824918 270)
			(size 0.519938 1.4986)
			(layers "F.Cu" "F.Mask" "F.Paste")
			(net "GND")
		)
		(pad "176" smd rect
			(at 2.050034 -36.975034 270)
			(size 0.519938 1.4986)
			(layers "F.Cu" "F.Mask" "F.Paste")
			(net "M_F_CPU0_SA_DQ<19>")
		)
		(pad "177" smd rect
			(at 2.050034 -36.124896 270)
			(size 0.519938 1.4986)
			(layers "F.Cu" "F.Mask" "F.Paste")
			(net "GND")
		)
		(pad "178" smd rect
			(at 2.050034 -35.275012 270)
			(size 0.519938 1.4986)
			(layers "F.Cu" "F.Mask" "F.Paste")
			(net "M_F_CPU0_SA_DQS_DN<7>")
		)
		(pad "179" smd rect
			(at 2.050034 -34.425128 270)
			(size 0.519938 1.4986)
			(layers "F.Cu" "F.Mask" "F.Paste")
			(net "M_F_CPU0_SA_DQS_DP<7>")
		)
		(pad "180" smd rect
			(at 2.050034 -33.57499 270)
			(size 0.519938 1.4986)
			(layers "F.Cu" "F.Mask" "F.Paste")
			(net "GND")
		)
		(pad "181" smd rect
			(at 2.050034 -32.725106 270)
			(size 0.519938 1.4986)
			(layers "F.Cu" "F.Mask" "F.Paste")
			(net "M_F_CPU0_SA_DQ<22>")
		)
		(pad "182" smd rect
			(at 2.050034 -31.874968 270)
			(size 0.519938 1.4986)
			(layers "F.Cu" "F.Mask" "F.Paste")
			(net "GND")
		)
	)
)
